(kicad_pcb
	(version 20241229)
	(generator "pcbnew")
	(generator_version "9.0")
	(general
		(thickness 1.62)
		(legacy_teardrops no)
	)
	(paper "A3")
	(title_block
		(title "COM Express 7 Baseboard")
		(date "2025-02-04")
		(rev "1.1.2")
		(company "Antmicro Ltd")
		(comment 1 "www.antmicro.com")
		(comment 9 "footprints 392-396 of 802")
	)
	(layers
		(0 "F.Cu" signal)
		(4 "In1.Cu" signal)
		(6 "In2.Cu" signal)
		(8 "In3.Cu" signal)
		(10 "In4.Cu" signal)
		(12 "In5.Cu" signal)
		(14 "In6.Cu" signal)
		(2 "B.Cu" signal)
		(9 "F.Adhes" user "F.Adhesive")
		(11 "B.Adhes" user "B.Adhesive")
		(13 "F.Paste" user)
		(15 "B.Paste" user)
		(5 "F.SilkS" user "F.Silkscreen")
		(7 "B.SilkS" user "B.Silkscreen")
		(1 "F.Mask" user)
		(3 "B.Mask" user)
		(17 "Dwgs.User" user "User.Drawings")
		(19 "Cmts.User" user "User.Comments")
		(21 "Eco1.User" user "User.Eco1")
		(23 "Eco2.User" user "User.Eco2")
		(25 "Edge.Cuts" user)
		(27 "Margin" user)
		(31 "F.CrtYd" user "F.Courtyard")
		(29 "B.CrtYd" user "B.Courtyard")
		(35 "F.Fab" user)
		(33 "B.Fab" user)
	)
	(footprint "antmicro-footprints:TP_SMD_0.75mm"
		(layer "F.Cu")
		(at 190.70861 72.802163 -90)
		(property "Reference" "TP97"
			(at 0 -0.6 90)
			(layer "F.SilkS")
			(hide yes)
			(effects
				(font
					(size 0.7 0.7)
					(thickness 0.15)
				)
				(justify right bottom)
			)
		)
		(property "Value" "TP_0.75mm_SMD"
			(at 0 1.2 90)
			(layer "F.Fab")
			(effects
				(font
					(size 0.7 0.7)
					(thickness 0.15)
				)
				(justify right bottom)
			)
		)
		(property "Author" "Antmicro"
			(at 117.906447 263.510773 0)
			(layer "F.Fab")
			(hide yes)
			(effects
				(font
					(size 1 1)
					(thickness 0.15)
				)
			)
		)
		(property "License" "Apache-2.0"
			(at 117.906447 263.510773 0)
			(layer "F.Fab")
			(hide yes)
			(effects
				(font
					(size 1 1)
					(thickness 0.15)
				)
			)
		)
		(property "MPN" ""
			(at 117.906447 263.510773 0)
			(layer "F.Fab")
			(hide yes)
			(effects
				(font
					(size 1 1)
					(thickness 0.15)
				)
			)
		)
		(property "Manufacturer" ""
			(at 117.906447 263.510773 0)
			(layer "F.Fab")
			(hide yes)
			(effects
				(font
					(size 1 1)
					(thickness 0.15)
				)
			)
		)
		(property "Public" "False"
			(at 117.906447 263.510773 0)
			(layer "F.Fab")
			(hide yes)
			(effects
				(font
					(size 1 1)
					(thickness 0.15)
				)
			)
		)
		(sheetname "Power")
		(sheetfile "power.kicad_sch")
		(attr exclude_from_pos_files exclude_from_bom)
		(fp_circle
			(center 0 0)
			(end 0.475 0)
			(stroke
				(width 0.05)
				(type default)
			)
			(fill no)
			(layer "F.CrtYd")
		)
		(pad "1" smd circle
			(at 0 0 270)
			(size 0.75 0.75)
			(layers "F.Cu" "F.Mask")
			(net 73 "+3V3_AON")
			(pinfunction "1")
			(pintype "passive")
			(teardrops
				(best_length_ratio 0.4)
				(max_length 1)
				(best_width_ratio 0.9)
				(max_width 2)
				(curved_edges yes)
				(filter_ratio 0.9)
				(enabled yes)
				(allow_two_segments yes)
				(prefer_zone_connections yes)
			)
		)
	)
	(footprint "antmicro-footprints:USON-10_2.5x1mm_P0.5mm"
		(layer "F.Cu")
		(at 107.6 152.2 -90)
		(descr "USON-10 2.5x1mm_ Pitch 0.5mm")
		(tags "USON-10 2.5x1mm Pitch 0.5mm")
		(property "Reference" "U9"
			(at -1.7 -0.78 0)
			(layer "F.SilkS")
			(effects
				(font
					(size 0.7 0.7)
					(thickness 0.15)
				)
				(justify right top)
			)
		)
		(property "Value" "ESD204DQAR"
			(at 0.018 2.499 90)
			(layer "F.Fab")
			(effects
				(font
					(size 0.7 0.7)
					(thickness 0.15)
				)
				(justify right top)
			)
		)
		(property "Datasheet" "https://www.ti.com/lit/ds/symlink/esd204.pdf?ts=1706004844383&ref_url=https%253A%252F%252Fwww.ti.com%252Finterface%252Fdiodes%252Fesd-protection-diodes%252Fproducts.html"
			(at 0 0 90)
			(layer "F.Fab")
			(hide yes)
			(effects
				(font
					(size 1.27 1.27)
					(thickness 0.15)
				)
			)
		)
		(property "Author" "Antmicro"
			(at 249.299 54.639 0)
			(layer "F.Fab")
			(hide yes)
			(effects
				(font
					(size 1 1)
					(thickness 0.15)
				)
			)
		)
		(property "License" "Apache-2.0"
			(at 249.299 54.639 0)
			(layer "F.Fab")
			(hide yes)
			(effects
				(font
					(size 1 1)
					(thickness 0.15)
				)
			)
		)
		(property "MPN" "ESD204DQAR"
			(at 249.299 54.639 0)
			(layer "F.Fab")
			(hide yes)
			(effects
				(font
					(size 1 1)
					(thickness 0.15)
				)
			)
		)
		(property "Manufacturer" "Texas Instruments"
			(at 249.299 54.639 0)
			(layer "F.Fab")
			(hide yes)
			(effects
				(font
					(size 1 1)
					(thickness 0.15)
				)
			)
		)
		(sheetname "OCuLink")
		(sheetfile "oculink.kicad_sch")
		(attr smd)
		(fp_line
			(start 0.498 1.398)
			(end -0.5 1.398)
			(stroke
				(width 0.15)
				(type solid)
			)
			(layer "F.SilkS")
		)
		(fp_line
			(start 0.498 -1.401)
			(end -0.5 -1.401)
			(stroke
				(width 0.15)
				(type solid)
			)
			(layer "F.SilkS")
		)
		(fp_circle
			(center -0.68 -1.27)
			(end -0.63 -1.27)
			(stroke
				(width 0.15)
				(type solid)
			)
			(fill yes)
			(layer "F.SilkS")
		)
		(fp_rect
			(start -0.8 -1.5)
			(end 0.8 1.499)
			(stroke
				(width 0.05)
				(type solid)
			)
			(fill no)
			(layer "F.CrtYd")
		)
		(fp_line
			(start -0.5 1.249)
			(end 0.498 1.249)
			(stroke
				(width 0.15)
				(type solid)
			)
			(layer "F.Fab")
		)
		(fp_line
			(start -0.5 -1)
			(end -0.5 1.249)
			(stroke
				(width 0.15)
				(type solid)
			)
			(layer "F.Fab")
		)
		(fp_line
			(start -0.25 -1.25)
			(end -0.5 -1)
			(stroke
				(width 0.15)
				(type solid)
			)
			(layer "F.Fab")
		)
		(fp_line
			(start 0.498 -1.25)
			(end 0.498 1.249)
			(stroke
				(width 0.15)
				(type solid)
			)
			(layer "F.Fab")
		)
		(fp_line
			(start 0.498 -1.25)
			(end -0.25 -1.25)
			(stroke
				(width 0.15)
				(type solid)
			)
			(layer "F.Fab")
		)
		(pad "1" smd roundrect
			(at -0.387 -1 180)
			(size 0.25 0.55)
			(layers "F.Cu" "F.Mask" "F.Paste")
			(roundrect_rratio 0.25)
			(net 194 "/OCuLink/PCIe_{x4}.RX2+")
			(pintype "passive")
			(teardrops
				(best_length_ratio 0.2)
				(max_length 1)
				(best_width_ratio 0.9)
				(max_width 2)
				(curved_edges yes)
				(filter_ratio 0.9)
				(enabled yes)
				(allow_two_segments yes)
				(prefer_zone_connections yes)
			)
		)
		(pad "2" smd roundrect
			(at -0.387 -0.5 180)
			(size 0.25 0.55)
			(layers "F.Cu" "F.Mask" "F.Paste")
			(roundrect_rratio 0.25)
			(net 195 "/OCuLink/PCIe_{x4}.RX2-")
			(pintype "passive")
			(teardrops
				(best_length_ratio 0.2)
				(max_length 1)
				(best_width_ratio 0.9)
				(max_width 2)
				(curved_edges yes)
				(filter_ratio 0.9)
				(enabled yes)
				(allow_two_segments yes)
				(prefer_zone_connections yes)
			)
		)
		(pad "3" smd roundrect
			(at -0.387 0 180)
			(size 0.4 0.55)
			(layers "F.Cu" "F.Mask" "F.Paste")
			(roundrect_rratio 0.25)
			(net 1 "GND")
			(pintype "power_in")
			(teardrops
				(best_length_ratio 0.2)
				(max_length 1)
				(best_width_ratio 0.9)
				(max_width 2)
				(curved_edges yes)
				(filter_ratio 0.9)
				(enabled yes)
				(allow_two_segments yes)
				(prefer_zone_connections yes)
			)
		)
		(pad "4" smd roundrect
			(at -0.387 0.498 180)
			(size 0.25 0.55)
			(layers "F.Cu" "F.Mask" "F.Paste")
			(roundrect_rratio 0.25)
			(net 196 "/OCuLink/PCIe_{x4}.RX3+")
			(pintype "passive")
			(teardrops
				(best_length_ratio 0.2)
				(max_length 1)
				(best_width_ratio 0.9)
				(max_width 2)
				(curved_edges yes)
				(filter_ratio 0.9)
				(enabled yes)
				(allow_two_segments yes)
				(prefer_zone_connections yes)
			)
		)
		(pad "5" smd roundrect
			(at -0.387 0.998 180)
			(size 0.25 0.55)
			(layers "F.Cu" "F.Mask" "F.Paste")
			(roundrect_rratio 0.25)
			(net 197 "/OCuLink/PCIe_{x4}.RX3-")
			(pintype "passive")
			(teardrops
				(best_length_ratio 0.2)
				(max_length 1)
				(best_width_ratio 0.9)
				(max_width 2)
				(curved_edges yes)
				(filter_ratio 0.9)
				(enabled yes)
				(allow_two_segments yes)
				(prefer_zone_connections yes)
			)
		)
		(pad "6" smd roundrect
			(at 0.385 0.998 180)
			(size 0.25 0.55)
			(layers "F.Cu" "F.Mask" "F.Paste")
			(roundrect_rratio 0.25)
			(net 197 "/OCuLink/PCIe_{x4}.RX3-")
			(pintype "passive")
			(teardrops
				(best_length_ratio 0.2)
				(max_length 1)
				(best_width_ratio 0.9)
				(max_width 2)
				(curved_edges yes)
				(filter_ratio 0.9)
				(enabled yes)
				(allow_two_segments yes)
				(prefer_zone_connections yes)
			)
		)
		(pad "7" smd roundrect
			(at 0.385 0.498 180)
			(size 0.25 0.55)
			(layers "F.Cu" "F.Mask" "F.Paste")
			(roundrect_rratio 0.25)
			(net 196 "/OCuLink/PCIe_{x4}.RX3+")
			(pintype "passive")
			(teardrops
				(best_length_ratio 0.2)
				(max_length 1)
				(best_width_ratio 0.9)
				(max_width 2)
				(curved_edges yes)
				(filter_ratio 0.9)
				(enabled yes)
				(allow_two_segments yes)
				(prefer_zone_connections yes)
			)
		)
		(pad "8" smd roundrect
			(at 0.385 0 180)
			(size 0.4 0.55)
			(layers "F.Cu" "F.Mask" "F.Paste")
			(roundrect_rratio 0.25)
			(net 1 "GND")
			(pintype "passive")
			(teardrops
				(best_length_ratio 0.2)
				(max_length 1)
				(best_width_ratio 0.9)
				(max_width 2)
				(curved_edges yes)
				(filter_ratio 0.9)
				(enabled yes)
				(allow_two_segments yes)
				(prefer_zone_connections yes)
			)
		)
		(pad "9" smd roundrect
			(at 0.385 -0.5 180)
			(size 0.25 0.55)
			(layers "F.Cu" "F.Mask" "F.Paste")
			(roundrect_rratio 0.25)
			(net 195 "/OCuLink/PCIe_{x4}.RX2-")
			(pintype "passive")
			(teardrops
				(best_length_ratio 0.2)
				(max_length 1)
				(best_width_ratio 0.9)
				(max_width 2)
				(curved_edges yes)
				(filter_ratio 0.9)
				(enabled yes)
				(allow_two_segments yes)
				(prefer_zone_connections yes)
			)
		)
		(pad "10" smd roundrect
			(at 0.385 -1 180)
			(size 0.25 0.55)
			(layers "F.Cu" "F.Mask" "F.Paste")
			(roundrect_rratio 0.25)
			(net 194 "/OCuLink/PCIe_{x4}.RX2+")
			(pintype "passive")
			(teardrops
				(best_length_ratio 0.2)
				(max_length 1)
				(best_width_ratio 0.9)
				(max_width 2)
				(curved_edges yes)
				(filter_ratio 0.9)
				(enabled yes)
				(allow_two_segments yes)
				(prefer_zone_connections yes)
			)
		)
	)
	(footprint "antmicro-footprints:R_0402_1005Metric"
		(layer "F.Cu")
		(at 308.275 76.362002)
		(descr "Resistor SMD 0402")
		(tags "resistor SMD 0402")
		(property "Reference" "R191"
			(at 0.775 0.397998 0)
			(layer "F.SilkS")
			(effects
				(font
					(size 0.7 0.7)
					(thickness 0.15)
				)
				(justify left bottom)
			)
		)
		(property "Value" "R_1k_0402"
			(at -1.011843 1.772047 0)
			(layer "F.Fab")
			(effects
				(font
					(size 0.7 0.7)
					(thickness 0.15)
				)
				(justify left bottom)
			)
		)
		(property "Datasheet" "https://www.bourns.com/docs/product-datasheets/cr.pdf"
			(at 0 0 0)
			(layer "F.Fab")
			(hide yes)
			(effects
				(font
					(size 1.27 1.27)
					(thickness 0.15)
				)
			)
		)
		(property "Author" "Antmicro"
			(at 0 0 0)
			(layer "F.Fab")
			(hide yes)
			(effects
				(font
					(size 1 1)
					(thickness 0.15)
				)
			)
		)
		(property "License" "Apache-2.0"
			(at 0 0 0)
			(layer "F.Fab")
			(hide yes)
			(effects
				(font
					(size 1 1)
					(thickness 0.15)
				)
			)
		)
		(property "MPN" "CR0402-FX-1001GLF"
			(at 0 0 0)
			(layer "F.Fab")
			(hide yes)
			(effects
				(font
					(size 1 1)
					(thickness 0.15)
				)
			)
		)
		(property "Manufacturer" "Bourns"
			(at 0 0 0)
			(layer "F.Fab")
			(hide yes)
			(effects
				(font
					(size 1 1)
					(thickness 0.15)
				)
			)
		)
		(property "Public" "False"
			(at 0 0 0)
			(layer "F.Fab")
			(hide yes)
			(effects
				(font
					(size 1 1)
					(thickness 0.15)
				)
			)
		)
		(property "Tolerance" "1%"
			(at 0 0 0)
			(layer "F.Fab")
			(hide yes)
			(effects
				(font
					(size 1 1)
					(thickness 0.15)
				)
			)
		)
		(property "Val" "1k"
			(at 0 0 0)
			(layer "F.Fab")
			(hide yes)
			(effects
				(font
					(size 1 1)
					(thickness 0.15)
				)
			)
		)
		(sheetname "PCIe misc")
		(sheetfile "pcie_misc.kicad_sch")
		(attr smd)
		(fp_rect
			(start -0.925 -0.47)
			(end 0.925 0.47)
			(stroke
				(width 0.05)
				(type default)
			)
			(fill no)
			(layer "F.CrtYd")
		)
		(fp_rect
			(start -0.5 -0.25)
			(end 0.5 0.25)
			(stroke
				(width 0.15)
				(type solid)
			)
			(fill no)
			(layer "F.Fab")
		)
		(pad "1" smd roundrect
			(at -0.48 0)
			(size 0.59 0.64)
			(layers "F.Cu" "F.Mask" "F.Paste")
			(roundrect_rratio 0.25)
			(net 610 "Net-(Y1-EN)")
			(pintype "passive")
			(teardrops
				(best_length_ratio 0.2)
				(max_length 1)
				(best_width_ratio 0.9)
				(max_width 2)
				(curved_edges yes)
				(filter_ratio 0.9)
				(enabled yes)
				(allow_two_segments yes)
				(prefer_zone_connections yes)
			)
		)
		(pad "2" smd roundrect
			(at 0.48 0)
			(size 0.59 0.64)
			(layers "F.Cu" "F.Mask" "F.Paste")
			(roundrect_rratio 0.25)
			(net 2 "+3V3")
			(pintype "passive")
			(teardrops
				(best_length_ratio 0.2)
				(max_length 1)
				(best_width_ratio 0.9)
				(max_width 2)
				(curved_edges yes)
				(filter_ratio 0.9)
				(enabled yes)
				(allow_two_segments yes)
				(prefer_zone_connections yes)
			)
		)
	)
	(footprint "antmicro-footprints:R_0402_1005Metric"
		(layer "F.Cu")
		(at 112.9 147.86 180)
		(descr "Resistor SMD 0402")
		(tags "resistor SMD 0402")
		(property "Reference" "R204"
			(at 0.85 -0.45 0)
			(layer "F.SilkS")
			(effects
				(font
					(size 0.7 0.7)
					(thickness 0.15)
				)
				(justify right bottom)
			)
		)
		(property "Value" "R_1k_0402"
			(at -1.011843 1.772047 0)
			(layer "F.Fab")
			(effects
				(font
					(size 0.7 0.7)
					(thickness 0.15)
				)
				(justify right bottom)
			)
		)
		(property "Datasheet" "https://www.bourns.com/docs/product-datasheets/cr.pdf"
			(at 0 0 180)
			(layer "F.Fab")
			(hide yes)
			(effects
				(font
					(size 1.27 1.27)
					(thickness 0.15)
				)
			)
		)
		(property "Author" "Antmicro"
			(at 225.8 295.72 0)
			(layer "F.Fab")
			(hide yes)
			(effects
				(font
					(size 1 1)
					(thickness 0.15)
				)
			)
		)
		(property "License" "Apache-2.0"
			(at 225.8 295.72 0)
			(layer "F.Fab")
			(hide yes)
			(effects
				(font
					(size 1 1)
					(thickness 0.15)
				)
			)
		)
		(property "MPN" "CR0402-FX-1001GLF"
			(at 225.8 295.72 0)
			(layer "F.Fab")
			(hide yes)
			(effects
				(font
					(size 1 1)
					(thickness 0.15)
				)
			)
		)
		(property "Manufacturer" "Bourns"
			(at 225.8 295.72 0)
			(layer "F.Fab")
			(hide yes)
			(effects
				(font
					(size 1 1)
					(thickness 0.15)
				)
			)
		)
		(property "Public" "False"
			(at 225.8 295.72 0)
			(layer "F.Fab")
			(hide yes)
			(effects
				(font
					(size 1 1)
					(thickness 0.15)
				)
			)
		)
		(property "Tolerance" "1%"
			(at 225.8 295.72 0)
			(layer "F.Fab")
			(hide yes)
			(effects
				(font
					(size 1 1)
					(thickness 0.15)
				)
			)
		)
		(property "Val" "1k"
			(at 225.8 295.72 0)
			(layer "F.Fab")
			(hide yes)
			(effects
				(font
					(size 1 1)
					(thickness 0.15)
				)
			)
		)
		(sheetname "PCIe redriver")
		(sheetfile "pcie_redriver.kicad_sch")
		(attr smd dnp)
		(fp_rect
			(start -0.925 -0.47)
			(end 0.925 0.47)
			(stroke
				(width 0.05)
				(type default)
			)
			(fill no)
			(layer "F.CrtYd")
		)
		(fp_rect
			(start -0.5 -0.25)
			(end 0.5 0.25)
			(stroke
				(width 0.15)
				(type solid)
			)
			(fill no)
			(layer "F.Fab")
		)
		(pad "1" smd roundrect
			(at -0.48 0 180)
			(size 0.59 0.64)
			(layers "F.Cu" "F.Mask" "F.Paste")
			(roundrect_rratio 0.25)
			(net 2 "+3V3")
			(pintype "passive")
			(teardrops
				(best_length_ratio 0.2)
				(max_length 1)
				(best_width_ratio 0.9)
				(max_width 2)
				(curved_edges yes)
				(filter_ratio 0.9)
				(enabled yes)
				(allow_two_segments yes)
				(prefer_zone_connections yes)
			)
		)
		(pad "2" smd roundrect
			(at 0.48 0 180)
			(size 0.59 0.64)
			(layers "F.Cu" "F.Mask" "F.Paste")
			(roundrect_rratio 0.25)
			(net 624 "/PCIe redriver/TX_EQ1")
			(pintype "passive")
			(teardrops
				(best_length_ratio 0.2)
				(max_length 1)
				(best_width_ratio 0.9)
				(max_width 2)
				(curved_edges yes)
				(filter_ratio 0.9)
				(enabled yes)
				(allow_two_segments yes)
				(prefer_zone_connections yes)
			)
		)
	)
	(footprint "antmicro-footprints:R_0402_1005Metric"
		(layer "F.Cu")
		(at 215.95 78.11)
		(descr "Resistor SMD 0402")
		(tags "resistor SMD 0402")
		(property "Reference" "R159"
			(at -1.35 1.35 0)
			(layer "F.SilkS")
			(effects
				(font
					(size 0.7 0.7)
					(thickness 0.15)
				)
				(justify left bottom)
			)
		)
		(property "Value" "R_2k2_0402"
			(at -1.011843 1.772047 0)
			(layer "F.Fab")
			(effects
				(font
					(size 0.7 0.7)
					(thickness 0.15)
				)
				(justify left bottom)
			)
		)
		(property "Datasheet" "https://www.bourns.com/docs/product-datasheets/cr.pdf"
			(at 0 0 0)
			(layer "F.Fab")
			(hide yes)
			(effects
				(font
					(size 1.27 1.27)
					(thickness 0.15)
				)
			)
		)
		(property "Author" "Antmicro"
			(at 0 0 0)
			(layer "F.Fab")
			(hide yes)
			(effects
				(font
					(size 1 1)
					(thickness 0.15)
				)
			)
		)
		(property "License" "Apache-2.0"
			(at 0 0 0)
			(layer "F.Fab")
			(hide yes)
			(effects
				(font
					(size 1 1)
					(thickness 0.15)
				)
			)
		)
		(property "MPN" "CR0402-FX-2201GLF"
			(at 0 0 0)
			(layer "F.Fab")
			(hide yes)
			(effects
				(font
					(size 1 1)
					(thickness 0.15)
				)
			)
		)
		(property "Manufacturer" "Bourns"
			(at 0 0 0)
			(layer "F.Fab")
			(hide yes)
			(effects
				(font
					(size 1 1)
					(thickness 0.15)
				)
			)
		)
		(property "Public" "False"
			(at 0 0 0)
			(layer "F.Fab")
			(hide yes)
			(effects
				(font
					(size 1 1)
					(thickness 0.15)
				)
			)
		)
		(property "Tolerance" "1%"
			(at 0 0 0)
			(layer "F.Fab")
			(hide yes)
			(effects
				(font
					(size 1 1)
					(thickness 0.15)
				)
			)
		)
		(property "Val" "2k2"
			(at 0 0 0)
			(layer "F.Fab")
			(hide yes)
			(effects
				(font
					(size 1 1)
					(thickness 0.15)
				)
			)
		)
		(sheetname "Com Express 7 MGMT")
		(sheetfile "com_express_7_mgmt.kicad_sch")
		(attr smd)
		(fp_rect
			(start -0.925 -0.47)
			(end 0.925 0.47)
			(stroke
				(width 0.05)
				(type default)
			)
			(fill no)
			(layer "F.CrtYd")
		)
		(fp_rect
			(start -0.5 -0.25)
			(end 0.5 0.25)
			(stroke
				(width 0.15)
				(type solid)
			)
			(fill no)
			(layer "F.Fab")
		)
		(pad "1" smd roundrect
			(at -0.48 0)
			(size 0.59 0.64)
			(layers "F.Cu" "F.Mask" "F.Paste")
			(roundrect_rratio 0.25)
			(net 1 "GND")
			(pintype "passive")
			(teardrops
				(best_length_ratio 0.2)
				(max_length 1)
				(best_width_ratio 0.9)
				(max_width 2)
				(curved_edges yes)
				(filter_ratio 0.9)
				(enabled yes)
				(allow_two_segments yes)
				(prefer_zone_connections yes)
			)
		)
		(pad "2" smd roundrect
			(at 0.48 0)
			(size 0.59 0.64)
			(layers "F.Cu" "F.Mask" "F.Paste")
			(roundrect_rratio 0.25)
			(net 523 "Net-(J13-Pad1)")
			(pintype "passive")
			(teardrops
				(best_length_ratio 0.2)
				(max_length 1)
				(best_width_ratio 0.9)
				(max_width 2)
				(curved_edges yes)
				(filter_ratio 0.9)
				(enabled yes)
				(allow_two_segments yes)
				(prefer_zone_connections yes)
			)
		)
	)
)
